#ISCELL
  logical_power cad_note *
  *
#ISCELL
  mstr_misc dns *
  *
#ISCELL
  pure_quanta quanta_title_block_c *
  *
#CELL
  pure_quanta 74lvc1g17gw *
  page152_i1
#CELL
  pure_quanta q_res *
  page152_i10
#ISCELL
  standard offpage *
  page152_i11
#ISCELL
  standard offpage *
  page152_i12
#CELL
  pure_quanta q_res *
  page152_i13
#ISCELL
  logical_power universal_gnd *
  page152_i14
#ISCELL
  standard offpage *
  page152_i2
#ISCELL
  standard offpage *
  page152_i21
#CELL
  pure_quanta q_cap *
  page152_i24
#ISCELL
  logical_power universal_gnd *
  page152_i25
#CELL
  pure_quanta q_res *
  page152_i26
#ISCELL
  standard offpage *
  page152_i29
#ISCELL
  logical_power universal_gnd *
  page152_i3
#ISCELL
  logical_power universal_gnd *
  page152_i32
#ISCELL
  logical_power universal_power *
  page152_i36
#CELL
  pure_quanta q_res *
  page152_i37
#ISCELL
  logical_power universal_power *
  page152_i38
#ISCELL
  standard offpage *
  page152_i39
#CELL
  pure_quanta q_cap *
  page152_i4
#CELL
  pure_quanta q_res *
  page152_i40
#ISCELL
  logical_power universal_power *
  page152_i41
#CELL
  pure_quanta q_res *
  page152_i42
#ISCELL
  logical_power universal_power *
  page152_i43
#CELL
  pure_quanta q_cap *
  page152_i44
#ISCELL
  logical_power universal_gnd *
  page152_i45
#CELL
  pure_quanta pi6cv304le *
  page152_i46
#ISCELL
  logical_power universal_power *
  page152_i47
#ISCELL
  logical_power universal_power *
  page152_i48
#CELL
  pure_quanta q_cap *
  page152_i49
#ISCELL
  logical_power universal_power *
  page152_i5
#ISCELL
  standard offpage *
  page152_i50
#ISCELL
  standard offpage *
  page152_i51
#CELL
  pure_quanta q_res *
  page152_i52
#CELL
  pure_quanta q_res *
  page152_i53
#ISCELL
  logical_power universal_gnd *
  page152_i54
#ISCELL
  logical_power universal_gnd *
  page152_i55
#CELL
  pure_quanta q_res *
  page152_i56
#ISCELL
  logical_power universal_gnd *
  page152_i57
#CELL
  pure_quanta q_cap *
  page152_i59
#CELL
  pure_quanta q_res *
  page152_i6
#ISCELL
  logical_power universal_gnd *
  page152_i60
#CELL
  pure_quanta q_res *
  page152_i61
#CELL
  pure_quanta q_res *
  page152_i62
#CELL
  pure_quanta 74lvc1g07gv *
  page152_i63
#CELL
  pure_quanta 74lvc1g07gv *
  page152_i65
#ISCELL
  logical_power universal_gnd *
  page152_i66
#ISCELL
  logical_power universal_power *
  page152_i67
#CELL
  pure_quanta q_cap *
  page152_i68
#ISCELL
  logical_power universal_gnd *
  page152_i69
#ISCELL
  standard offpage *
  page152_i7
#ISCELL
  standard offpage *
  page152_i70
#CELL
  pure_quanta q_res *
  page152_i71
#ISCELL
  logical_power universal_power *
  page152_i72
#ISCELL
  logical_power universal_power *
  page152_i73
#CELL
  pure_quanta q_res *
  page152_i74
#CELL
  pure_quanta q_res *
  page152_i75
#CELL
  pure_quanta q_osc4p *
  page152_i76
#ISCELL
  standard offpage *
  page152_i77
#CELL
  pure_quanta q_res *
  page152_i78
#CELL
  pure_quanta 74lvc1g126se7 *
  page152_i79
#CELL
  pure_quanta q_res *
  page152_i8
#ISCELL
  logical_power universal_gnd *
  page152_i80
#ISCELL
  standard offpage *
  page152_i83
#ISCELL
  logical_power universal_gnd *
  page152_i84
#ISCELL
  logical_power universal_power *
  page152_i85
#ISCELL
  logical_power universal_gnd *
  page152_i86
#CELL
  pure_quanta q_cap *
  page152_i87
#ISCELL
  standard offpage *
  page152_i88
#ISCELL
  standard offpage *
  page152_i9
#CELL
  pure_quanta q_res *
  page152_i90
#ISCELL
  standard offpage *
  page152_i91
#CELL
  pure_quanta 74lvc1g66gv *
  page152_i92
